# BASEBOARD_FAB2 (Tioga Pass) — schematic netlist excerpt (pin names and nets, part order shuffled) for the footprints in the layout excerpt that follows; sources: Cadence DE-HDL packaged netlist, KiCad conversion of Wiwynn_Tioga_Pass_MB.brd

C4G24  CAP  22UF 4V 20% X6S  pkg 0805LF  page 221 : A = PVTT_ABC ; B = GND
C2D14  CAP_A  22.0UF 4V 20% X6S  pkg 0603V  page 76 : A = PVCCIN_CPU1 ; B = GND

(kicad_pcb
	(version 20260206)
	(generator "pcbnew")
	(generator_version "10.0")
	(general
		(thickness 1.6)
		(legacy_teardrops no)
	)
	(paper "A4")
	(title_block
		(title "Wiwynn_Tioga_Pass_MB.brd")
		(comment 1 "Tioga Pass / footprints 2139-2140 of 4770")
	)
	(layers
		(0 "F.Cu" signal "TOP")
		(4 "In1.Cu" signal "L2GND")
		(6 "In2.Cu" signal "L3")
		(8 "In3.Cu" signal "L4GND")
		(10 "In4.Cu" signal "L5")
		(12 "In5.Cu" signal "L6GND")
		(14 "In6.Cu" signal "L7VCC")
		(16 "In7.Cu" signal "L8VCC")
		(18 "In8.Cu" signal "L9GND")
		(20 "In9.Cu" signal "L10")
		(22 "In10.Cu" signal "L11GND")
		(24 "In11.Cu" signal "L12")
		(26 "In12.Cu" signal "L13GND")
		(2 "B.Cu" signal "BOTTOM")
		(9 "F.Adhes" user "F.Adhesive")
		(11 "B.Adhes" user "B.Adhesive")
		(13 "F.Paste" user "Package Geometry/Pastemask Top")
		(15 "B.Paste" user "Package Geometry/Pastemask Bottom")
		(5 "F.SilkS" user "Ref Des/Silkscreen Top")
		(7 "B.SilkS" user "Ref Des/Silkscreen Bottom")
		(1 "F.Mask" user "Board Geometry/Soldermask Top")
		(3 "B.Mask" user "Board Geometry/Soldermask Bottom")
		(17 "Dwgs.User" user "User.Drawings")
		(19 "Cmts.User" user "User.Comments")
		(21 "Eco1.User" user "User.Eco1")
		(23 "Eco2.User" user "User.Eco2")
		(25 "Edge.Cuts" user "Board Geometry/Outline")
		(27 "Margin" user)
		(31 "F.CrtYd" user "Package Geometry/Place Bound Top")
		(29 "B.CrtYd" user "Package Geometry/Place Bound Bottom")
		(35 "F.Fab" user "Ref Des/Assembly Top")
		(33 "B.Fab" user "Ref Des/Assembly Bottom")
	)
	(footprint ""
		(layer "F.Cu")
		(at 184.260998 2.679192 -90)
		(property "Reference" "C4G24"
			(at 0 0 270)
			(layer "F.SilkS")
			(hide yes)
			(effects
				(font
					(size 1.27 1.27)
				)
			)
		)
		(property "Value" ""
			(at 0 0 270)
			(layer "F.Fab")
			(effects
				(font
					(size 1.27 1.27)
				)
			)
		)
		(duplicate_pad_numbers_are_jumpers no)
		(fp_rect
			(start 0.7239 1.9939)
			(end -0.7239 -0.2159)
			(stroke
				(width 0)
				(type default)
			)
			(fill no)
			(layer "F.CrtYd")
		)
		(fp_line
			(start -0.7239 1.9939)
			(end 0.7239 1.9939)
			(stroke
				(width 0.1)
				(type default)
			)
			(layer "F.Fab")
		)
		(fp_line
			(start 0.7239 1.9939)
			(end 0.7239 -0.2159)
			(stroke
				(width 0.1)
				(type default)
			)
			(layer "F.Fab")
		)
		(fp_line
			(start -0.7239 -0.2159)
			(end -0.7239 1.9939)
			(stroke
				(width 0.1)
				(type default)
			)
			(layer "F.Fab")
		)
		(fp_line
			(start 0.7239 -0.2159)
			(end -0.7239 -0.2159)
			(stroke
				(width 0.1)
				(type default)
			)
			(layer "F.Fab")
		)
		(pad "1" smd rect
			(at 0 0 270)
			(size 1.27 1.016)
			(layers "F.Cu" "F.Mask" "F.Paste")
			(net "PVTT_ABC")
		)
		(pad "2" smd rect
			(at 0 1.778 270)
			(size 1.27 1.016)
			(layers "F.Cu" "F.Mask" "F.Paste")
			(net "GND")
		)
		(zone
			(layer "F.Cu")
			(hatch none 0.5)
			(connect_pads
				(clearance 0)
			)
			(min_thickness 0.25)
			(keepout
				(tracks not_allowed)
				(vias allowed)
				(pads allowed)
				(copperpour not_allowed)
				(footprints allowed)
			)
			(placement
				(enabled no)
				(sheetname "")
			)
			(fill
				(thermal_gap 0.5)
				(thermal_bridge_width 0.5)
				(island_removal_mode 0)
			)
			(polygon
				(pts
					(xy 182.990998 3.314192) (xy 183.752998 3.314192) (xy 183.752998 2.044192) (xy 182.990998 2.044192)
				)
			)
		)
	)
	(footprint ""
		(layer "F.Cu")
		(at 99.438968 -79.6036 180)
		(property "Reference" "C2D14"
			(at 0 0 180)
			(layer "F.SilkS")
			(hide yes)
			(effects
				(font
					(size 1.27 1.27)
				)
			)
		)
		(property "Value" ""
			(at 0 0 180)
			(layer "F.Fab")
			(effects
				(font
					(size 1.27 1.27)
				)
			)
		)
		(duplicate_pad_numbers_are_jumpers no)
		(fp_poly
			(pts
				(xy -0.4953 -0.2032) (xy 0.4953 -0.2032) (xy 0.4953 1.6002) (xy -0.4953 1.6002)
			)
			(stroke
				(width 0)
				(type default)
			)
			(fill no)
			(layer "F.CrtYd")
		)
		(fp_line
			(start 0.4953 1.6002)
			(end -0.4953 1.6002)
			(stroke
				(width 0.1)
				(type default)
			)
			(layer "F.Fab")
		)
		(fp_line
			(start 0.4953 -0.2032)
			(end 0.4953 1.6002)
			(stroke
				(width 0.1)
				(type default)
			)
			(layer "F.Fab")
		)
		(fp_line
			(start -0.4953 1.6002)
			(end -0.4953 -0.2032)
			(stroke
				(width 0.1)
				(type default)
			)
			(layer "F.Fab")
		)
		(fp_line
			(start -0.4953 -0.2032)
			(end 0.4953 -0.2032)
			(stroke
				(width 0.1)
				(type default)
			)
			(layer "F.Fab")
		)
		(pad "1" smd rect
			(at 0 0 180)
			(size 0.762 0.889)
			(layers "F.Cu" "F.Mask" "F.Paste")
			(net "PVCCIN_CPU1")
		)
		(pad "2" smd rect
			(at 0 1.397 180)
			(size 0.762 0.889)
			(layers "F.Cu" "F.Mask" "F.Paste")
			(net "GND")
		)
		(zone
			(layer "F.Cu")
			(hatch none 0.5)
			(connect_pads
				(clearance 0)
			)
			(min_thickness 0.25)
			(keepout
				(tracks not_allowed)
				(vias allowed)
				(pads allowed)
				(copperpour not_allowed)
				(footprints allowed)
			)
			(placement
				(enabled no)
				(sheetname "")
			)
			(fill
				(thermal_gap 0.5)
				(thermal_bridge_width 0.5)
				(island_removal_mode 0)
			)
			(polygon
				(pts
					(xy 99.819968 -80.0481) (xy 99.057968 -80.0481) (xy 99.057968 -80.5561) (xy 99.819968 -80.5561)
				)
			)
		)
	)
)
